# T6G (Grand Teton) — schematic netlist excerpt (pin names and nets, part order shuffled) for the footprints in the layout excerpt that follows; sources: Cadence DE-HDL packaged netlist, KiCad conversion of 04192023_DAF0TMB3IC0_F0TG_MB_C_brd_V02_OCP.brd

PR6552  Q_RES  2.2 5% CHIP  pkg 0402LF  page 363 : A = P0V9_RETIMER_CPU0_PVCC ; B = P0V9_RETIMER_CPU0_VCC1
R111  Q_RES  1K 1% EMPTY  pkg 0402LF  page 105 : A = P3V3 ; B = PWRGD_CHH_CPU1_DIMM
PC558_3  Q_CAP  22UF 16V 20% X6S  pkg C0805  page 195 : A = SW_P12V_AUX_PVDDCR_CPU0_P0_FLT ; B = GND

(kicad_pcb
	(version 20260206)
	(generator "pcbnew")
	(generator_version "10.0")
	(general
		(thickness 1.6)
		(legacy_teardrops no)
	)
	(paper "A4")
	(title_block
		(title "04192023_DAF0TMB3IC0_F0TG_MB_C_brd_V02_OCP.brd")
		(comment 1 "Grand Teton / footprints 7166-7168 of 8354")
	)
	(layers
		(0 "F.Cu" signal "TOP")
		(4 "In1.Cu" signal "GND")
		(6 "In2.Cu" signal "IN1")
		(8 "In3.Cu" signal "GND1")
		(10 "In4.Cu" signal "IN2")
		(12 "In5.Cu" signal "GND2")
		(14 "In6.Cu" signal "IN3")
		(16 "In7.Cu" signal "GND3")
		(18 "In8.Cu" signal "VCC")
		(20 "In9.Cu" signal "VCC1")
		(22 "In10.Cu" signal "GND4")
		(24 "In11.Cu" signal "IN4")
		(26 "In12.Cu" signal "GND5")
		(28 "In13.Cu" signal "IN5")
		(30 "In14.Cu" signal "GND6")
		(32 "In15.Cu" signal "IN6")
		(34 "In16.Cu" signal "GND7")
		(2 "B.Cu" signal "BOTTOM")
		(9 "F.Adhes" user "F.Adhesive")
		(11 "B.Adhes" user "B.Adhesive")
		(13 "F.Paste" user "Package Geometry/Pastemask Top")
		(15 "B.Paste" user "Package Geometry/Pastemask Bottom")
		(5 "F.SilkS" user "Ref Des/Silkscreen Top")
		(7 "B.SilkS" user "Ref Des/Silkscreen Bottom")
		(1 "F.Mask" user "Board Geometry/Soldermask Top")
		(3 "B.Mask" user "Board Geometry/Soldermask Bottom")
		(17 "Dwgs.User" user "User.Drawings")
		(19 "Cmts.User" user "User.Comments")
		(21 "Eco1.User" user "User.Eco1")
		(23 "Eco2.User" user "User.Eco2")
		(25 "Edge.Cuts" user "Board Geometry/Outline")
		(27 "Margin" user)
		(31 "F.CrtYd" user "Package Geometry/Place Bound Top")
		(29 "B.CrtYd" user "Package Geometry/Place Bound Bottom")
		(35 "F.Fab" user "Ref Des/Assembly Top")
		(33 "B.Fab" user "Ref Des/Assembly Bottom")
	)
	(footprint ""
		(layer "B.Cu")
		(at 172.727874 -193.996564)
		(property "Reference" "R111"
			(at 0 0 0)
			(layer "B.SilkS")
			(hide yes)
			(effects
				(font
					(size 1.27 1.27)
				)
				(justify mirror)
			)
		)
		(property "Value" ""
			(at 0 0 0)
			(layer "B.Fab")
			(effects
				(font
					(size 1.27 1.27)
				)
				(justify mirror)
			)
		)
		(duplicate_pad_numbers_are_jumpers no)
		(fp_line
			(start -0.7874 -0.4064)
			(end -0.7874 0.4064)
			(stroke
				(width 0.1524)
				(type default)
			)
			(layer "B.SilkS")
		)
		(fp_line
			(start -0.7874 0.4064)
			(end 0.7874 0.4064)
			(stroke
				(width 0.1524)
				(type default)
			)
			(layer "B.SilkS")
		)
		(fp_line
			(start 0.7874 -0.4064)
			(end -0.7874 -0.4064)
			(stroke
				(width 0.1524)
				(type default)
			)
			(layer "B.SilkS")
		)
		(fp_line
			(start 0.7874 0.4064)
			(end 0.7874 -0.4064)
			(stroke
				(width 0.1524)
				(type default)
			)
			(layer "B.SilkS")
		)
		(fp_line
			(start -0.67945 -0.3048)
			(end -0.67945 0.3048)
			(stroke
				(width 0.1)
				(type default)
			)
			(layer "B.Fab")
		)
		(fp_line
			(start -0.67945 0.3048)
			(end -0.120396 0.3048)
			(stroke
				(width 0.1)
				(type default)
			)
			(layer "B.Fab")
		)
		(fp_line
			(start -0.12065 -0.3048)
			(end -0.67945 -0.3048)
			(stroke
				(width 0.1)
				(type default)
			)
			(layer "B.Fab")
		)
		(fp_line
			(start -0.12065 -0.2794)
			(end -0.12065 -0.3048)
			(stroke
				(width 0.1)
				(type default)
			)
			(layer "B.Fab")
		)
		(fp_line
			(start -0.120396 0.2794)
			(end 0.12065 0.2794)
			(stroke
				(width 0.1)
				(type default)
			)
			(layer "B.Fab")
		)
		(fp_line
			(start -0.120396 0.3048)
			(end -0.120396 0.2794)
			(stroke
				(width 0.1)
				(type default)
			)
			(layer "B.Fab")
		)
		(fp_line
			(start 0.12065 -0.305054)
			(end 0.12065 -0.2794)
			(stroke
				(width 0.1)
				(type default)
			)
			(layer "B.Fab")
		)
		(fp_line
			(start 0.12065 -0.2794)
			(end -0.12065 -0.2794)
			(stroke
				(width 0.1)
				(type default)
			)
			(layer "B.Fab")
		)
		(fp_line
			(start 0.12065 0.2794)
			(end 0.12065 0.3048)
			(stroke
				(width 0.1)
				(type default)
			)
			(layer "B.Fab")
		)
		(fp_line
			(start 0.12065 0.3048)
			(end 0.67945 0.3048)
			(stroke
				(width 0.1)
				(type default)
			)
			(layer "B.Fab")
		)
		(fp_line
			(start 0.67945 -0.305054)
			(end 0.12065 -0.305054)
			(stroke
				(width 0.1)
				(type default)
			)
			(layer "B.Fab")
		)
		(fp_line
			(start 0.67945 0.3048)
			(end 0.67945 -0.305054)
			(stroke
				(width 0.1)
				(type default)
			)
			(layer "B.Fab")
		)
		(pad "1" smd circle
			(at 0.40005 0 180)
			(size 0 0)
			(layers "B.Cu" "B.Mask" "B.Paste")
			(net "P3V3")
		)
		(pad "2" smd circle
			(at -0.40005 0 180)
			(size 0 0)
			(layers "B.Cu" "B.Mask" "B.Paste")
			(net "PWRGD_CHH_CPU1_DIMM")
		)
	)
	(footprint ""
		(layer "B.Cu")
		(at 380.051056 -182.867554 -90)
		(property "Reference" "PC558_3"
			(at 0 0 90)
			(layer "B.SilkS")
			(hide yes)
			(effects
				(font
					(size 1.27 1.27)
				)
				(justify mirror)
			)
		)
		(property "Value" ""
			(at 0 0 90)
			(layer "B.Fab")
			(effects
				(font
					(size 1.27 1.27)
				)
				(justify mirror)
			)
		)
		(duplicate_pad_numbers_are_jumpers no)
		(fp_line
			(start -1.524 0.762)
			(end 1.524 0.762)
			(stroke
				(width 0.1524)
				(type default)
			)
			(layer "B.SilkS")
		)
		(fp_line
			(start 1.524 0.762)
			(end 1.524 -0.762)
			(stroke
				(width 0.1524)
				(type default)
			)
			(layer "B.SilkS")
		)
		(fp_line
			(start -1.524 -0.762)
			(end -1.524 0.762)
			(stroke
				(width 0.1524)
				(type default)
			)
			(layer "B.SilkS")
		)
		(fp_line
			(start 1.524 -0.762)
			(end -1.524 -0.762)
			(stroke
				(width 0.1524)
				(type default)
			)
			(layer "B.SilkS")
		)
		(fp_line
			(start -1.1049 0.724916)
			(end -1.1049 -0.724916)
			(stroke
				(width 0.1)
				(type default)
			)
			(layer "B.Fab")
		)
		(fp_line
			(start 1.1049 0.724916)
			(end -1.1049 0.724916)
			(stroke
				(width 0.1)
				(type default)
			)
			(layer "B.Fab")
		)
		(fp_line
			(start -1.1049 -0.724916)
			(end 1.1049 -0.724916)
			(stroke
				(width 0.1)
				(type default)
			)
			(layer "B.Fab")
		)
		(fp_line
			(start 1.1049 -0.724916)
			(end 1.1049 0.724916)
			(stroke
				(width 0.1)
				(type default)
			)
			(layer "B.Fab")
		)
		(pad "1" smd rect
			(at 0.889 0 270)
			(size 1.016 1.27)
			(layers "B.Cu" "B.Mask" "B.Paste")
			(net "SW_P12V_AUX_PVDDCR_CPU0_P0_FLT")
		)
		(pad "2" smd rect
			(at -0.889 0 270)
			(size 1.016 1.27)
			(layers "B.Cu" "B.Mask" "B.Paste")
			(net "GND")
		)
	)
	(footprint ""
		(layer "B.Cu")
		(at 442.345826 -399.56359 -90)
		(property "Reference" "PR6552"
			(at 0 0 90)
			(layer "B.SilkS")
			(hide yes)
			(effects
				(font
					(size 1.27 1.27)
				)
				(justify mirror)
			)
		)
		(property "Value" ""
			(at 0 0 90)
			(layer "B.Fab")
			(effects
				(font
					(size 1.27 1.27)
				)
				(justify mirror)
			)
		)
		(duplicate_pad_numbers_are_jumpers no)
		(fp_line
			(start -0.7874 0.4064)
			(end 0.7874 0.4064)
			(stroke
				(width 0.1524)
				(type default)
			)
			(layer "B.SilkS")
		)
		(fp_line
			(start 0.7874 0.4064)
			(end 0.7874 -0.4064)
			(stroke
				(width 0.1524)
				(type default)
			)
			(layer "B.SilkS")
		)
		(fp_line
			(start -0.7874 -0.4064)
			(end -0.7874 0.4064)
			(stroke
				(width 0.1524)
				(type default)
			)
			(layer "B.SilkS")
		)
		(fp_line
			(start 0.7874 -0.4064)
			(end -0.7874 -0.4064)
			(stroke
				(width 0.1524)
				(type default)
			)
			(layer "B.SilkS")
		)
		(fp_line
			(start -0.67945 0.3048)
			(end -0.120396 0.3048)
			(stroke
				(width 0.1)
				(type default)
			)
			(layer "B.Fab")
		)
		(fp_line
			(start -0.120396 0.3048)
			(end -0.120396 0.2794)
			(stroke
				(width 0.1)
				(type default)
			)
			(layer "B.Fab")
		)
		(fp_line
			(start 0.12065 0.3048)
			(end 0.67945 0.3048)
			(stroke
				(width 0.1)
				(type default)
			)
			(layer "B.Fab")
		)
		(fp_line
			(start 0.67945 0.3048)
			(end 0.67945 -0.305054)
			(stroke
				(width 0.1)
				(type default)
			)
			(layer "B.Fab")
		)
		(fp_line
			(start -0.120396 0.2794)
			(end 0.12065 0.2794)
			(stroke
				(width 0.1)
				(type default)
			)
			(layer "B.Fab")
		)
		(fp_line
			(start 0.12065 0.2794)
			(end 0.12065 0.3048)
			(stroke
				(width 0.1)
				(type default)
			)
			(layer "B.Fab")
		)
		(fp_line
			(start -0.12065 -0.2794)
			(end -0.12065 -0.3048)
			(stroke
				(width 0.1)
				(type default)
			)
			(layer "B.Fab")
		)
		(fp_line
			(start 0.12065 -0.2794)
			(end -0.12065 -0.2794)
			(stroke
				(width 0.1)
				(type default)
			)
			(layer "B.Fab")
		)
		(fp_line
			(start -0.67945 -0.3048)
			(end -0.67945 0.3048)
			(stroke
				(width 0.1)
				(type default)
			)
			(layer "B.Fab")
		)
		(fp_line
			(start -0.12065 -0.3048)
			(end -0.67945 -0.3048)
			(stroke
				(width 0.1)
				(type default)
			)
			(layer "B.Fab")
		)
		(fp_line
			(start 0.12065 -0.305054)
			(end 0.12065 -0.2794)
			(stroke
				(width 0.1)
				(type default)
			)
			(layer "B.Fab")
		)
		(fp_line
			(start 0.67945 -0.305054)
			(end 0.12065 -0.305054)
			(stroke
				(width 0.1)
				(type default)
			)
			(layer "B.Fab")
		)
		(pad "1" smd circle
			(at 0.40005 0 90)
			(size 0 0)
			(layers "B.Cu" "B.Mask" "B.Paste")
			(net "P0V9_RETIMER_CPU0_PVCC")
		)
		(pad "2" smd circle
			(at -0.40005 0 90)
			(size 0 0)
			(layers "B.Cu" "B.Mask" "B.Paste")
			(net "P0V9_RETIMER_CPU0_VCC1")
		)
	)
)
